# T6G (Grand Teton) — schematic parts with pin connectivity, parts 7289–7441 of 8303; source: Cadence DE-HDL packaged netlist (pstxprt.dat, pstxnet.dat, pstchip.dat)

R4569  Q_RES  0 5% EMPTY  pkg 0402LF  page 124 : 1 = GPU_3V3IO_RSVD1 ; 2 = GPU_3V3IO_RSVD1_ISO
R4570  Q_RES  0 5% EMPTY  pkg 0402LF  page 124 : 1 = GPU_3V3IO_RSVD3 ; 2 = GPU_3V3IO_RSVD3_ISO
R4571  Q_RES  0 5% EMPTY  pkg 0402LF  page 124 : 1 = GPU_3V3IO_RSVD4 ; 2 = GPU_3V3IO_RSVD4_ISO
R4572  Q_RES  0 5% EMPTY  pkg 0402LF  page 125 : 1 = GPU_3V3IO_RSVD1_FFU ; 2 = GPU_3V3IO_RSVD1_FFU_ISO
R4573  Q_RES  0 5% EMPTY  pkg 0402LF  page 125 : 1 = PRSNT_CABLE_GPU_B3_N ; 2 = PRSNT_CABLE_GPU_B3_ISO_N
R4574  Q_RES  0 5% EMPTY  pkg 0402LF  page 125 : 1 = PRSNT_CABLE_GPU_A1_N ; 2 = PRSNT_CABLE_GPU_A1_ISO_N
R4575  Q_RES  0 5% EMPTY  pkg 0402LF  page 125 : 1 = GPU_3V3IO_RSVD0_FFU ; 2 = GPU_3V3IO_RSVD0_FFU_ISO
R4576  Q_RES  0 5% EMPTY  pkg 0402LF  page 125 : 1 = GPU_3V3IO_RSVD5_FFU ; 2 = GPU_3V3IO_RSVD5_FFU_ISO
R4577  Q_RES  0 5% EMPTY  pkg 0402LF  page 125 : 1 = GPU_3V3IO_RSVD3_FFU ; 2 = GPU_3V3IO_RSVD3_FFU_ISO
R4578  Q_RES  0 5% EMPTY  pkg 0402LF  page 125 : 1 = PRSNT_CABLE_GPU_A2_N ; 2 = PRSNT_CABLE_GPU_A2_ISO_N
R4601  Q_RES  0 5% CHIP  pkg 0402LF  page 133 : 1 = CLK_50M_NCSI_OCP_SFF_ISO ; 2 = CLK_50M_NCSI_OCP_SFF_ISO_R
R4602  Q_RES  0 5% CHIP  pkg 0402LF  page 139 : 1 = CLK_50M_NCSI_OCP_V3_2_ISO ; 2 = CLK_50M_NCSI_OCP_V3_2_ISO_R
R4603  Q_RES  10K 1% CHIP  pkg 0402LF  page 248 : 1 = SMB_BMC_GPU_EN ; 2 = GND
R4604  Q_RES  4.7K 5% CHIP  pkg 0402LF  page 253 : 1 = P3V3_AUX ; 2 = PWRGD_PS_PWROK_PLD_N
R4605  Q_RES  1K 1% CHIP  pkg 0402LF  page 253 : 1 = P3V3_AUX ; 2 = PWRGD_PS_PWROK_PLD_ISO
R4608  Q_RES  33.2 1% CHIP  pkg 0402LF  page 81 : 1 = GPU_FPGA_RST_R_N ; 2 = GPU_FPGA_RST_N
R4620  Q_RES  1K 1% EMPTY  pkg 0402LF  page 268 : 1 = P3V3_AUX ; 2 = IRQ_UV_DETECT_N
R4638  Q_RES  243 1% CHIP  pkg 1206LF  page 188 : 1 = P5V ; 2 = VR_P5V_EN_D
R4639  Q_RES  243 1% CHIP  pkg 1206LF  page 188 : 1 = P5V ; 2 = VR_P5V_EN_D
R4640  Q_RES  243 1% CHIP  pkg 1206LF  page 188 : 1 = P5V ; 2 = VR_P5V_EN_D
R4641  Q_RES  243 1% CHIP  pkg 1206LF  page 188 : 1 = P5V ; 2 = VR_P5V_EN_D
R4809  Q_RES  0 5% CHIP  pkg 0402LF  page 150 : 1 = TP_CHASI ; 2 = GND
R4901  Q_RES  82K 1% CHIP  pkg 0402LF  page 268 : 1 = P12V_PSU_FUSE ; 2 = HSC_EN
R5004  Q_RES  10K 1% CHIP  pkg 0402LF  page 161 : 1 = SMB_APML_CPU1_R_SDA ; 2 = GND
R5006  Q_RES  1K 1% EMPTY  pkg 0402LF  page 159 : 1 = PVDD11_S3_P0 ; 2 = I3C_SPD_DDRAF_CPU0_LVC1_SCL
R5007  Q_RES  1K 1% EMPTY  pkg 0402LF  page 159 : 1 = PVDD11_S3_P0 ; 2 = I3C_SPD_DDRAF_CPU0_LVC1_SDA
R5008  Q_RES  1K 1% EMPTY  pkg 0402LF  page 159 : 1 = PVDD11_S3_P0 ; 2 = I3C_SPD_DDRGL_CPU0_LVC1_SCL
R5009  Q_RES  1K 1% EMPTY  pkg 0402LF  page 159 : 1 = PVDD11_S3_P0 ; 2 = I3C_SPD_DDRGL_CPU0_LVC1_SDA
R5010  Q_RES  1K 1% EMPTY  pkg 0402LF  page 159 : 1 = PVDD11_S3_P1 ; 2 = I3C_SPD_DDRAF_CPU1_LVC1_SCL
R5011  Q_RES  1K 1% EMPTY  pkg 0402LF  page 159 : 1 = PVDD11_S3_P1 ; 2 = I3C_SPD_DDRAF_CPU1_LVC1_SDA
R5012  Q_RES  1K 1% EMPTY  pkg 0402LF  page 159 : 1 = PVDD11_S3_P1 ; 2 = I3C_SPD_DDRGL_CPU1_LVC1_SCL
R5013  Q_RES  1K 1% EMPTY  pkg 0402LF  page 159 : 1 = PVDD11_S3_P1 ; 2 = I3C_SPD_DDRGL_CPU1_LVC1_SDA
R5014  Q_RES  1K 1% EMPTY  pkg 0402LF  page 159 : 1 = PVDD11_S3_P0 ; 2 = I3C_SCM_0_R_SCL
R5015  Q_RES  1K 1% EMPTY  pkg 0402LF  page 159 : 1 = PVDD11_S3_P0 ; 2 = I3C_SCM_0_R_SDA
R5016  Q_RES  1K 1% EMPTY  pkg 0402LF  page 159 : 1 = PVDD11_S3_P0 ; 2 = I3C_SCM_1_R_SCL
R5017  Q_RES  1K 1% EMPTY  pkg 0402LF  page 159 : 1 = PVDD11_S3_P0 ; 2 = I3C_SCM_1_R_SDA
R5018  Q_RES  1K 1% EMPTY  pkg 0402LF  page 159 : 1 = PVDD11_S3_P1 ; 2 = I3C_SCM_2_R_SCL
R5019  Q_RES  1K 1% EMPTY  pkg 0402LF  page 159 : 1 = PVDD11_S3_P1 ; 2 = I3C_SCM_2_R_SDA
R5020  Q_RES  1K 1% EMPTY  pkg 0402LF  page 159 : 1 = PVDD11_S3_P1 ; 2 = I3C_SCM_3_R_SCL
R5021  Q_RES  1K 1% EMPTY  pkg 0402LF  page 159 : 1 = PVDD11_S3_P1 ; 2 = I3C_SCM_3_R_SDA
R5026  Q_RES  4.7K 5% EMPTY  pkg 0402LF  page 28 : 1 = GND ; 2 = FM_SMM_CRASHDUMP
R5027  Q_RES  4.7K 5% EMPTY  pkg 0402LF  page 28 : 1 = GND ; 2 = IRQ_SMI_ACTIVE_N
R5028  Q_RES  4.7K 5% EMPTY  pkg 0402LF  page 28 : 1 = GND ; 2 = IRQ_BMC_SMI_N
R5029  Q_RES  4.7K 5% EMPTY  pkg 0402LF  page 28 : 1 = GND ; 2 = IRQ_TPM_SPI_R_N
R5030  Q_RES  4.7K 5% EMPTY  pkg 0402LF  page 55 : 1 = GND ; 2 = FM_BMC_TPM_PRES_N
R5031  Q_RES  4.7K 5% EMPTY  pkg 0402LF  page 55 : 1 = GND ; 2 = FM_BMC_READY_N
R5032  Q_RES  4.7K 5% EMPTY  pkg 0402LF  page 55 : 1 = GND ; 2 = IRQ_CPU_BMC_NMI_N
R5051  Q_RES  0 5% EMPTY  pkg 0402LF  page 187 : 1 = P3V3_RTC_AUX ; 2 = P1V5_BAT_IN
R5052  Q_RES  0 5% CHIP  pkg 0402LF  page 187 : 1 = P3V3_RTC_AUX_R ; 2 = P3V3_RTC_AUX
R5053  Q_RES  1K 1% EMPTY  pkg 0402LF  page 187 : 1 = P1V5_BAT_OUT ; 2 = P1V5_BAT_OUT_R
R5054  Q_RES  0 5% CHIP  pkg 0402LF  page 187 : 1 = P3V3_RTC_AUX_R ; 2 = P1V5_BAT_OUT_R
R5055  Q_RES  10K 5% CHIP  pkg 0402LF  page 27 : 1 = P1V5_BAT ; 2 = CPU0_RTC_LDO_SELECT
R5056  Q_RES  10K 5% EMPTY  pkg 0402LF  page 27 : 1 = CPU0_RTC_LDO_SELECT ; 2 = GND
R5071  Q_RES  100 1% CHIP  pkg 0402LF  page 167 : 1 = P1V8_AUX ; 2 = FM_FORCE_ALL_PWRON_ON
R5099  Q_RES  0 5% CHIP  pkg 0402LF  page 81 : 1 = FPGA_DEBUG_SW_SPARE ; 2 = FM_FPGA_DEBUG_SW_SPARE
R5101  Q_RES  10K 5% CHIP  pkg 0402LF  page 187 : 1 = P3V3_AUX ; 2 = P3V3_STBY_R
R5102  Q_RES  49.9 1% CHIP  pkg 0402LF  page 28 : 1 = XTAL_CPU0_X48M_X2 ; 2 = XTAL_CPU0_X48M_X2_R
R5103  Q_RES  49.9 1% CHIP  pkg 0402LF  page 55 : 1 = XTAL_CPU1_X48M_X2 ; 2 = XTAL_CPU1_X48M_X2_R
R5234  Q_RES  0 5% CHIP  pkg 0402LF  page 234 : 1 = USB2_HUB_BUF_SWB_R_DP ; 2 = USB2_HUB_BUF_SWB_DP
R5236  Q_RES  0 5% CHIP  pkg 0402LF  page 234 : 1 = USB2_HUB_BUF_SWB_R_DN ; 2 = USB2_HUB_BUF_SWB_DN
R5238  Q_RES  3.9K 5% EMPTY  pkg 0402LF  page 234 : 1 = PD_U5201_EQ ; 2 = GND
R5377  Q_RES  0 5% CHIP  pkg 0402LF  page 144 : 1 = HDD_ACTIVITY_BUF_N ; 2 = PU_BUFFER_HDD_ACTIVITY
R5487  Q_RES  0 5% EMPTY  pkg 0402LF  page 134 : 1 = P3V3_OCP_SFF_EN_R ; 2 = P3V3_OCP_EN_1_R
R6000  Q_RES  0 5% CHIP  pkg 0402LF  page 150 : 1 = I3C_SCM_0_SCL ; 2 = I3C_SCM_0_R_SCL
R6001  Q_RES  0 5% CHIP  pkg 0402LF  page 150 : 1 = I3C_SCM_0_SDA ; 2 = I3C_SCM_0_R_SDA
R6002  Q_RES  0 5% CHIP  pkg 0402LF  page 150 : 1 = I3C_SCM_1_SCL ; 2 = I3C_SCM_1_R_SCL
R6003  Q_RES  0 5% CHIP  pkg 0402LF  page 150 : 1 = I3C_SCM_1_SDA ; 2 = I3C_SCM_1_R_SDA
R6004  Q_RES  0 5% CHIP  pkg 0402LF  page 150 : 1 = I3C_SCM_2_SCL ; 2 = I3C_SCM_2_R_SCL
R6005  Q_RES  0 5% CHIP  pkg 0402LF  page 150 : 1 = I3C_SCM_2_SDA ; 2 = I3C_SCM_2_R_SDA
R6006  Q_RES  0 5% CHIP  pkg 0402LF  page 150 : 1 = I3C_SCM_3_SCL ; 2 = I3C_SCM_3_R_SCL
R6007  Q_RES  0 5% CHIP  pkg 0402LF  page 150 : 1 = I3C_SCM_3_SDA ; 2 = I3C_SCM_3_R_SDA
R6008  Q_RES  0 5% CHIP  pkg 0402LF  page 150 : 1 = SGPIO_SCM_DO_<0> ; 2 = SGPIO_SCM_DO_R_<0>
R6009  Q_RES  0 5% CHIP  pkg 0402LF  page 150 : 1 = SGPIO_SCM_CLK_<0> ; 2 = SGPIO_SCM_CLK_R_<0>
R6010  Q_RES  0 5% CHIP  pkg 0402LF  page 150 : 1 = SGPIO_SCM_DI_<0> ; 2 = SGPIO_SCM_DI_R_<0>
R6011  Q_RES  0 5% CHIP  pkg 0402LF  page 150 : 1 = SGPIO_SCM_LD_<0> ; 2 = SGPIO_SCM_LD_R_<0>
R6012  Q_RES  0 5% CHIP  pkg 0402LF  page 150 : 1 = SGPIO_SCM_DO_<1> ; 2 = SGPIO_SCM_DO_R_<1>
R6013  Q_RES  0 5% CHIP  pkg 0402LF  page 150 : 1 = SGPIO_SCM_CLK_<1> ; 2 = SGPIO_SCM_CLK_R_<1>
R6014  Q_RES  0 5% CHIP  pkg 0402LF  page 150 : 1 = SGPIO_SCM_DI_<1> ; 2 = SGPIO_SCM_DI_R_<1>
R6015  Q_RES  0 5% CHIP  pkg 0402LF  page 150 : 1 = SGPIO_SCM_LD_<1> ; 2 = SGPIO_SCM_LD_R_<1>
R6016  Q_RES  2K 5% EMPTY  pkg 0402LF  page 151 : 1 = P3V3_AUX ; 2 = SGPIO_SCM_DO_<0>
R6017  Q_RES  2K 5% EMPTY  pkg 0402LF  page 151 : 1 = P3V3_AUX ; 2 = SGPIO_SCM_CLK_<0>
R6018  Q_RES  2K 5% EMPTY  pkg 0402LF  page 151 : 1 = P3V3_AUX ; 2 = SGPIO_SCM_DI_<0>
R6019  Q_RES  2K 5% EMPTY  pkg 0402LF  page 151 : 1 = P3V3_AUX ; 2 = SGPIO_SCM_LD_<0>
R6020  Q_RES  2K 5% EMPTY  pkg 0402LF  page 151 : 1 = P3V3_AUX ; 2 = SGPIO_SCM_DO_<1>
R6021  Q_RES  2K 5% EMPTY  pkg 0402LF  page 151 : 1 = P3V3_AUX ; 2 = SGPIO_SCM_CLK_<1>
R6022  Q_RES  2K 5% EMPTY  pkg 0402LF  page 151 : 1 = P3V3_AUX ; 2 = SGPIO_SCM_DI_<1>
R6023  Q_RES  2K 5% EMPTY  pkg 0402LF  page 151 : 1 = P3V3_AUX ; 2 = SGPIO_SCM_LD_<1>
R6024  Q_RES  4.7K 5% EMPTY  pkg 0402LF  page 151 : 1 = P3V3_AUX ; 2 = SGPIO_SCM_INTR_N
R6025  Q_RES  0 5% CHIP  pkg 0402LF  page 150 : 1 = SGPIO_SCM_RESET_N ; 2 = SGPIO_SCM_RESET_R_N
R6026  Q_RES  0 5% CHIP  pkg 0402LF  page 150 : 1 = SGPIO_SCM_INTR_N ; 2 = SGPIO_SCM_INTR_R1_N
R6027  Q_RES  4.7K 5% EMPTY  pkg 0402LF  page 151 : 1 = SGPIO_SCM_RESET_N ; 2 = GND
R6028  Q_RES  0 5% CHIP  pkg 0402LF  page 150 : 1 = FM_LPC_ESPI_SEL ; 2 = GND
R6029  Q_RES  33 5% CHIP  pkg 0402LF  page 80 : 1 = CLK_GEN2_BMC_RC_OE_N ; 2 = CLK_GEN2_BMC_RC_OE_R_N
R6030  Q_RES  33 5% CHIP  pkg 0402LF  page 80 : 1 = CLK_GEN2_GPU_FPGA_OE_N ; 2 = CLK_GEN2_GPU_FPGA_OE_R_N
R6031  Q_RES  33 5% CHIP  pkg 0402LF  page 80 : 1 = VIRTUAL_RESEAT_FPGA_N ; 2 = VIRTUAL_RESEAT_FPGA_R_N
R6032  Q_RES  0 5% CHIP  pkg 0402LF  page 150 : 1 = JTAG_SCM_DBREQ_N ; 2 = SCM_HDT_DBREQ_N
R6033  Q_RES  0 5% CHIP  pkg 0402LF  page 150 : 1 = RST_MB_STBY_N ; 2 = RST_MB_STBY_R_N
R6034  Q_RES  1K 1% CHIP  pkg 0402LF  page 150 : 1 = P3V3_AUX ; 2 = SCM_ROT_CPU_RST_R_N
R6035  Q_RES  4.7K 5% EMPTY  pkg 0402LF  page 150 : 1 = SCM_ROT_CPU_RST_R_N ; 2 = GND
R6036  Q_RES  2K 1% EMPTY  pkg 0402LF  page 151 : 1 = SMB_1_PLD_3V3AUX_SCL ; 2 = P3V3_AUX
R6037  Q_RES  2K 1% EMPTY  pkg 0402LF  page 151 : 1 = SMB_1_PLD_3V3AUX_SDA ; 2 = P3V3_AUX
R6038  Q_RES  0 5% CHIP  pkg 0402LF  page 80 : 1 = UV_ALERT_N ; 2 = IRQ_UV_DETECT_N
R6039  Q_RES  0 5% CHIP  pkg 0402LF  page 80 : 1 = OC_ALERT_N ; 2 = HSC_D_OC
R6040  Q_RES  10K 5% CHIP  pkg 0402LF  page 167 : 1 = P1V8_AUX ; 2 = PU_FPGA_DEBUG_LED_CTRL
R6041  Q_RES  100K 1% CHIP  pkg 0402LF  page 167 : 1 = GND ; 2 = FPGA_DEBUG_LED_CTRL
R6042  Q_RES  10K 5% CHIP  pkg 0402LF  page 167 : 1 = P3V3_AUX ; 2 = PU_FPGA_DEBUG_SW_SPARE
R6043  Q_RES  100K 1% CHIP  pkg 0402LF  page 167 : 1 = GND ; 2 = FPGA_DEBUG_SW_SPARE
R6044  Q_RES  10K 5% CHIP  pkg 0402LF  page 167 : 1 = FM_FORCE_ALL_PWRON ; 2 = GND
R6045  Q_RES  4.7K 5% EMPTY  pkg 0402LF  page 134 : 1 = P12V_OCP_EN_1_R ; 2 = GND
R6046  Q_RES  100 1% CHIP  pkg 0402LF  page 81 : 1 = HP_LVC3_OCP_SFF_PRSNT2_PLD_N ; 2 = PRSNT_OCP_SFF_N
R6047  Q_RES  0 5% CHIP  pkg 0402LF  page 81 : 1 = PWRGD_P3V3_AUX ; 2 = PWRGD_P3V3_AUX_R
R6048  Q_RES  0 5% CHIP  pkg 0402LF  page 81 : 1 = HP_LVC3_E1S_0_HSC_PWRGD ; 2 = P12V_E1S_0_PWRGD
R6049  Q_RES  4.7K 5% CHIP  pkg 0402LF  page 146 : 1 = P3V3_E1S_EN_0_R ; 2 = GND
R6050  Q_RES  100K 1% EMPTY  pkg 0402LF  page 188 : 1 = SW_P3V3_EN ; 2 = GND
R6051  Q_RES  0 5% CHIP  pkg 0402LF  page 82 : 1 = P12V_OCP_V3_1_PWRGD ; 2 = P12V_OCP_V3_1_PLD_PWRGD
R6052  Q_RES  0 5% CHIP  pkg 0402LF  page 82 : 1 = E1S_0_PRSNT_R_N ; 2 = E1S_0_PRSNT_N
R6053  Q_RES  0 5% CHIP  pkg 0402LF  page 82 : 1 = M2_SSD0_CLKREQ_EN_N ; 2 = FM_CLKREQ_M2_1_N
R6054  Q_RES  0 5% CHIP  pkg 0402LF  page 82 : 1 = FM_OCP_SFF_PWR_GOOD ; 2 = PWRGD_OCP_SFF_PWR_GOOD
R6055  Q_RES  0 5% CHIP  pkg 0402LF  page 81 : 1 = HP_LVC3_SCM_HSC_PWRGD ; 2 = P12V_SCM_PWRGD_R
R6056  Q_RES  0 5% CHIP  pkg 0402LF  page 139 : 1 = RST_PERST_OCP_V3_2_BUF2_N ; 2 = RST_PERST0_OCP_V3_2_N
R6057  Q_RES  0 5% CHIP  pkg 0402LF  page 139 : 1 = RST_PERST_OCP_V3_2_BUF2_N ; 2 = RST_PERST1_OCP_V3_2_N
R6058  Q_RES  0 5% CHIP  pkg 0402LF  page 139 : 1 = RST_PERST_OCP_V3_2_BUF2_N ; 2 = RST_PERST2_OCP_V3_2_N
R6059  Q_RES  0 5% CHIP  pkg 0402LF  page 139 : 1 = RST_PERST_OCP_V3_2_BUF2_N ; 2 = RST_PERST3_OCP_V3_2_N
R6060  Q_RES  4.7K 5% EMPTY  pkg 0402LF  page 140 : 1 = P12V_OCP_EN_2_R ; 2 = GND
R6061  Q_RES  4.7K 5% EMPTY  pkg 0402LF  page 83 : 1 = P12V_OCP_V3_2_EN_R ; 2 = P3V3_AUX
R6062  Q_RES  4.7K 5% EMPTY  pkg 0402LF  page 83 : 1 = P3V3_OCP_V3_2_EN_R ; 2 = P3V3_AUX
R6063  Q_RES  33 5% CHIP  pkg 0402LF  page 155 : 1 = IRQ_OCP_V3_2_WAKE_BUF_N ; 2 = IRQ_LVC3_WAKE_N
R6064  Q_RES  0 5% EMPTY  pkg 0402LF  page 150 : 1 = UART_CPU0_SCM_LVC3_UART1_RX ; 2 = UART_CPU0_SCM_LVC3_UART1_R_RX
R6065  Q_RES  0 5% EMPTY  pkg 0402LF  page 150 : 1 = UART_CPU0_SCM_LVC3_UART1_R1_TX ; 2 = UART_CPU0_SCM_LVC3_UART1_TX
R6066  Q_RES  0 5% EMPTY  pkg 0402LF  page 151 : 1 = JTAG_SCM_TDI_R ; 2 = JTAG_SCM_TDI
R6067  Q_RES  0 5% CHIP  pkg 0402LF  page 151 : 1 = JTAG_SCM_TDO_R ; 2 = JTAG_SCM_TDI
R6068  Q_RES  0 5% EMPTY  pkg 0402LF  page 151 : 1 = JTAG_SCM_TDO_R ; 2 = JTAG_SCM_TDO
R6069  Q_RES  0 5% CHIP  pkg 0402LF  page 151 : 1 = JTAG_SCM_TDI_R ; 2 = JTAG_SCM_TDO
R6070  Q_RES  4.7K 5% EMPTY  pkg 0402LF  page 151 : 1 = P3V3_AUX ; 2 = JTAG_SCM_DBREQ_N
R6071  Q_RES  4.7K 5% EMPTY  pkg 0402LF  page 150 : 1 = P3V3_AUX ; 2 = PU_JTAG_DBP_BMC_PRDY_N
R6073  Q_RES  0 5% CHIP  pkg 0402LF  page 82 : 1 = FM_PDB_BUF_EN_R_N ; 2 = FM_PDB_BUF_EN_N
R6074  Q_RES  0 5% CHIP  pkg 0402LF  page 85 : 1 = FM_THERMAL_ALERT_N ; 2 = FM_THERMAL_ALERT_R_N
R6075  Q_RES  0 5% CHIP  pkg 0402LF  page 85 : 1 = LED_HDD_ACTIVITY_B_N ; 2 = LED_HDD_ACTIVITY_B_PLD_N
R6076  Q_RES  33 5% CHIP  pkg 0402LF  page 151 : 1 = SMB_SCM_2_R3_SCL ; 2 = SMB_SCM_2_R4_SCL
R6077  Q_RES  33 5% CHIP  pkg 0402LF  page 151 : 1 = SMB_SCM_2_R3_SDA ; 2 = SMB_SCM_2_R4_SDA
R6078  Q_RES  0 5% CHIP  pkg 0402LF  page 85 : 1 = PWRGD_P3V3_AUX ; 2 = PWRGD_P3V3_AUX_PDB
R6081  Q_RES  4.7K 5% CHIP  pkg 0402LF  page 28 : 1 = PVDD11_S3_P0 ; 2 = SMB_CPU0_2_SCL
R6082  Q_RES  4.7K 5% CHIP  pkg 0402LF  page 28 : 1 = PVDD11_S3_P0 ; 2 = SMB_CPU0_2_SDA
R6083  Q_RES  4.7K 5% CHIP  pkg 0402LF  page 28 : 1 = PVDD11_S3_P0 ; 2 = SMB_CPU0_3_SCL
R6084  Q_RES  4.7K 5% CHIP  pkg 0402LF  page 28 : 1 = PVDD11_S3_P0 ; 2 = SMB_CPU0_3_SDA
R6085  Q_RES  10K 1% CHIP  pkg 0402LF  page 81 : 1 = P3V3_AUX ; 2 = PU_SPI_PLD_CS_N
R6086  Q_RES  10K 1% EMPTY  pkg 0402LF  page 200 : 1 = PVDDIO_P0_EN_R ; 2 = GND
R6087  Q_RES  10K 1% EMPTY  pkg 0402LF  page 210 : 1 = PVDDCR_SOC_P1_EN_RC ; 2 = GND
R6088  Q_RES  10K 1% EMPTY  pkg 0402LF  page 217 : 1 = PVDDIO_P1_EN_R ; 2 = GND
R6089  Q_RES  10K 1% EMPTY  pkg 0402LF  page 193 : 1 = PVDDCR_SOC_P0_EN_RC ; 2 = GND
R6090  Q_RES  4.7K 5% CHIP  pkg 0402LF  page 85 : 1 = JTAG_SCM_PLD_TCK ; 2 = GND
R6092  Q_RES  0 5% CHIP  pkg 0402LF  page 85 : 1 = SCM_SYS_PWROK_R ; 2 = SCM_SYS_PWROK_R1
R6093  Q_RES  0 5% CHIP  pkg 0402LF  page 85 : 1 = SCM_SYS_PWROK_R ; 2 = SCM_SYS_PWROK_R2
